(kicad_pcb
	(version 20260206)
	(generator "pcbnew")
	(generator_version "10.0")
	(general
		(thickness 1.6)
		(legacy_teardrops no)
	)
	(paper "A4")
	(title_block
		(title "Bryce Canyon_IOM_IOC_16318-2_OCP.brd")
		(comment 1 "Bryce Canyon / footprints 261-264 of 1605")
	)
	(layers
		(0 "F.Cu" signal "TOP")
		(4 "In1.Cu" signal "L2GND")
		(6 "In2.Cu" signal "L3")
		(8 "In3.Cu" signal "L4VCC")
		(10 "In4.Cu" signal "L5VCC")
		(12 "In5.Cu" signal "L6")
		(14 "In6.Cu" signal "L7GND")
		(2 "B.Cu" signal "BOTTOM")
		(9 "F.Adhes" user "F.Adhesive")
		(11 "B.Adhes" user "B.Adhesive")
		(13 "F.Paste" user "Package Geometry/Pastemask Top")
		(15 "B.Paste" user "Package Geometry/Pastemask Bottom")
		(5 "F.SilkS" user "Ref Des/Silkscreen Top")
		(7 "B.SilkS" user "Ref Des/Silkscreen Bottom")
		(1 "F.Mask" user "Board Geometry/Soldermask Top")
		(3 "B.Mask" user "Board Geometry/Soldermask Bottom")
		(17 "Dwgs.User" user "User.Drawings")
		(19 "Cmts.User" user "User.Comments")
		(21 "Eco1.User" user "User.Eco1")
		(23 "Eco2.User" user "User.Eco2")
		(25 "Edge.Cuts" user "Board Geometry/Outline")
		(27 "Margin" user)
		(31 "F.CrtYd" user "Package Geometry/Place Bound Top")
		(29 "B.CrtYd" user "Package Geometry/Place Bound Bottom")
		(35 "F.Fab" user "Ref Des/Assembly Top")
		(33 "B.Fab" user "Ref Des/Assembly Bottom")
	)
	(footprint ""
		(layer "F.Cu")
		(at 88.9 -12.649962)
		(property "Reference" "USB1"
			(at 0 0 0)
			(layer "F.SilkS")
			(hide yes)
			(effects
				(font
					(size 1.27 1.27)
				)
			)
		)
		(property "Value" "SKT-USB13-246-GP"
			(at 4.9149 11.7348 0)
			(unlocked yes)
			(layer "F.Fab")
			(hide yes)
			(effects
				(font
					(size 1.016 1.016)
					(thickness 0.1524)
				)
			)
		)
		(property "Device Type" "SKT-USB13-064258"
			(at 4.9149 10.2108 0)
			(unlocked yes)
			(layer "F.Fab")
			(hide yes)
			(effects
				(font
					(size 1.016 1.016)
					(thickness 0.1524)
				)
			)
		)
		(duplicate_pad_numbers_are_jumpers no)
		(fp_line
			(start -3.827526 -10.395204)
			(end -3.827526 -11.004804)
			(stroke
				(width 0.3048)
				(type default)
			)
			(layer "F.SilkS")
		)
		(fp_line
			(start -3.827526 0.6477)
			(end -3.827526 -0.6477)
			(stroke
				(width 0.3048)
				(type default)
			)
			(layer "F.SilkS")
		)
		(fp_line
			(start -3.7211 -12.8016)
			(end 3.7211 -12.8016)
			(stroke
				(width 0.1524)
				(type default)
			)
			(layer "F.SilkS")
		)
		(fp_line
			(start -3.7211 -9.5758)
			(end -3.7211 -12.8016)
			(stroke
				(width 0.1524)
				(type default)
			)
			(layer "F.SilkS")
		)
		(fp_line
			(start -3.7211 -1.4732)
			(end -3.4671 -1.4732)
			(stroke
				(width 0.1524)
				(type default)
			)
			(layer "F.SilkS")
		)
		(fp_line
			(start -3.7211 1.4732)
			(end -3.7211 -1.4732)
			(stroke
				(width 0.1524)
				(type default)
			)
			(layer "F.SilkS")
		)
		(fp_line
			(start -3.4671 -9.5758)
			(end -3.7211 -9.5758)
			(stroke
				(width 0.1524)
				(type default)
			)
			(layer "F.SilkS")
		)
		(fp_line
			(start -3.4671 -1.4732)
			(end -3.4671 -9.5758)
			(stroke
				(width 0.1524)
				(type default)
			)
			(layer "F.SilkS")
		)
		(fp_line
			(start -3.4671 1.4732)
			(end -3.7211 1.4732)
			(stroke
				(width 0.1524)
				(type default)
			)
			(layer "F.SilkS")
		)
		(fp_line
			(start -3.4671 12.649962)
			(end -3.4671 1.4732)
			(stroke
				(width 0.1524)
				(type default)
			)
			(layer "F.SilkS")
		)
		(fp_line
			(start -3.4671 13.462)
			(end -3.4671 12.649962)
			(stroke
				(width 0.1524)
				(type default)
			)
			(layer "F.SilkS")
		)
		(fp_line
			(start -1.592326 -11.004804)
			(end -1.592326 -10.395204)
			(stroke
				(width 0.3048)
				(type default)
			)
			(layer "F.SilkS")
		)
		(fp_line
			(start -1.592326 -0.6477)
			(end -1.592326 0.6477)
			(stroke
				(width 0.3048)
				(type default)
			)
			(layer "F.SilkS")
		)
		(fp_line
			(start 1.592326 -10.052304)
			(end 1.592326 -11.347704)
			(stroke
				(width 0.3048)
				(type default)
			)
			(layer "F.SilkS")
		)
		(fp_line
			(start 1.592326 0.3048)
			(end 1.592326 -0.3048)
			(stroke
				(width 0.3048)
				(type default)
			)
			(layer "F.SilkS")
		)
		(fp_line
			(start 3.4671 -9.2202)
			(end 3.4671 -1.1303)
			(stroke
				(width 0.1524)
				(type default)
			)
			(layer "F.SilkS")
		)
		(fp_line
			(start 3.4671 -1.1303)
			(end 3.7211 -1.1303)
			(stroke
				(width 0.1524)
				(type default)
			)
			(layer "F.SilkS")
		)
		(fp_line
			(start 3.4671 1.1303)
			(end 3.4671 12.649962)
			(stroke
				(width 0.1524)
				(type default)
			)
			(layer "F.SilkS")
		)
		(fp_line
			(start 3.4671 12.649962)
			(end -3.4671 12.649962)
			(stroke
				(width 0.1524)
				(type default)
			)
			(layer "F.SilkS")
		)
		(fp_line
			(start 3.4671 12.649962)
			(end 3.4671 13.462)
			(stroke
				(width 0.1524)
				(type default)
			)
			(layer "F.SilkS")
		)
		(fp_line
			(start 3.4671 13.462)
			(end -3.4671 13.462)
			(stroke
				(width 0.1524)
				(type default)
			)
			(layer "F.SilkS")
		)
		(fp_line
			(start 3.7211 -12.8016)
			(end 3.7211 -9.2202)
			(stroke
				(width 0.1524)
				(type default)
			)
			(layer "F.SilkS")
		)
		(fp_line
			(start 3.7211 -9.2202)
			(end 3.4671 -9.2202)
			(stroke
				(width 0.1524)
				(type default)
			)
			(layer "F.SilkS")
		)
		(fp_line
			(start 3.7211 -1.1303)
			(end 3.7211 1.1303)
			(stroke
				(width 0.1524)
				(type default)
			)
			(layer "F.SilkS")
		)
		(fp_line
			(start 3.7211 1.1303)
			(end 3.4671 1.1303)
			(stroke
				(width 0.1524)
				(type default)
			)
			(layer "F.SilkS")
		)
		(fp_line
			(start 3.827526 -11.347704)
			(end 3.827526 -10.052304)
			(stroke
				(width 0.3048)
				(type default)
			)
			(layer "F.SilkS")
		)
		(fp_line
			(start 3.827526 -0.3048)
			(end 3.827526 0.3048)
			(stroke
				(width 0.3048)
				(type default)
			)
			(layer "F.SilkS")
		)
		(fp_arc
			(start -3.827526 -11.004804)
			(mid -2.709926 -12.122404)
			(end -1.592326 -11.004804)
			(stroke
				(width 0.3048)
				(type default)
			)
			(layer "F.SilkS")
		)
		(fp_arc
			(start -3.827526 -0.6477)
			(mid -2.709926 -1.7653)
			(end -1.592326 -0.6477)
			(stroke
				(width 0.3048)
				(type default)
			)
			(layer "F.SilkS")
		)
		(fp_arc
			(start -1.592326 -10.395204)
			(mid -2.709926 -9.277604)
			(end -3.827526 -10.395204)
			(stroke
				(width 0.3048)
				(type default)
			)
			(layer "F.SilkS")
		)
		(fp_arc
			(start -1.592326 0.6477)
			(mid -2.709926 1.7653)
			(end -3.827526 0.6477)
			(stroke
				(width 0.3048)
				(type default)
			)
			(layer "F.SilkS")
		)
		(fp_arc
			(start 1.592326 -11.347704)
			(mid 2.709926 -12.465304)
			(end 3.827526 -11.347704)
			(stroke
				(width 0.3048)
				(type default)
			)
			(layer "F.SilkS")
		)
		(fp_arc
			(start 1.592326 -0.3048)
			(mid 2.709926 -1.4224)
			(end 3.827526 -0.3048)
			(stroke
				(width 0.3048)
				(type default)
			)
			(layer "F.SilkS")
		)
		(fp_arc
			(start 1.607566 -9.8679)
			(mid 1.596126 -9.959786)
			(end 1.592326 -10.052304)
			(stroke
				(width 0.3048)
				(type default)
			)
			(layer "F.SilkS")
		)
		(fp_arc
			(start 1.783588 -9.426956)
			(mid 0.074258 -9.000444)
			(end 1.607566 -9.8679)
			(stroke
				(width 0.3048)
				(type default)
			)
			(layer "F.SilkS")
		)
		(fp_arc
			(start 3.827526 -10.052304)
			(mid 3.036889 -8.983601)
			(end 1.783588 -9.426956)
			(stroke
				(width 0.3048)
				(type default)
			)
			(layer "F.SilkS")
		)
		(fp_arc
			(start 3.827526 0.3048)
			(mid 2.709926 1.4224)
			(end 1.592326 0.3048)
			(stroke
				(width 0.3048)
				(type default)
			)
			(layer "F.SilkS")
		)
		(fp_circle
			(center -0.899922 -8.830056)
			(end -0.010922 -8.830056)
			(stroke
				(width 0.3048)
				(type default)
			)
			(fill no)
			(layer "F.SilkS")
		)
		(fp_circle
			(center -0.899922 -6.329934)
			(end -0.010922 -6.329934)
			(stroke
				(width 0.3048)
				(type default)
			)
			(fill no)
			(layer "F.SilkS")
		)
		(fp_circle
			(center -0.899922 -4.329938)
			(end -0.010922 -4.329938)
			(stroke
				(width 0.3048)
				(type default)
			)
			(fill no)
			(layer "F.SilkS")
		)
		(fp_circle
			(center -0.899922 -1.829816)
			(end -0.010922 -1.829816)
			(stroke
				(width 0.3048)
				(type default)
			)
			(fill no)
			(layer "F.SilkS")
		)
		(fp_circle
			(center -0.899922 -1.829816)
			(end -0.010922 -1.829816)
			(stroke
				(width 0.3048)
				(type default)
			)
			(fill no)
			(layer "F.SilkS")
		)
		(fp_circle
			(center 0.899922 -7.329932)
			(end 1.788922 -7.329932)
			(stroke
				(width 0.3048)
				(type default)
			)
			(fill no)
			(layer "F.SilkS")
		)
		(fp_circle
			(center 0.899922 -5.329936)
			(end 1.788922 -5.329936)
			(stroke
				(width 0.3048)
				(type default)
			)
			(fill no)
			(layer "F.SilkS")
		)
		(fp_circle
			(center 0.899922 -3.32994)
			(end 1.788922 -3.32994)
			(stroke
				(width 0.3048)
				(type default)
			)
			(fill no)
			(layer "F.SilkS")
		)
		(fp_circle
			(center 0.899922 -1.329944)
			(end 1.788922 -1.329944)
			(stroke
				(width 0.3048)
				(type default)
			)
			(fill no)
			(layer "F.SilkS")
		)
		(fp_circle
			(center 0.899922 -1.329944)
			(end 1.788922 -1.329944)
			(stroke
				(width 0.3048)
				(type default)
			)
			(fill no)
			(layer "F.SilkS")
		)
		(fp_rect
			(start -3.2131 13.208)
			(end 3.2131 -12.5476)
			(stroke
				(width 0)
				(type default)
			)
			(fill no)
			(layer "F.CrtYd")
		)
		(fp_poly
			(pts
				(xy -3.7211 13.716) (xy -3.7211 1.7272) (xy -3.9751 1.7272) (xy -3.9751 -1.7272) (xy -3.7211 -1.7272)
				(xy -3.7211 -9.3218) (xy -3.9751 -9.3218) (xy -3.9751 -13.0556) (xy 3.9751 -13.0556) (xy 3.9751 -8.9662)
				(xy 3.7211 -8.9662) (xy 3.7211 -1.3843) (xy 3.9751 -1.3843) (xy 3.9751 -0.00635) (xy 3.2131 -0.00635)
				(xy 3.2131 -12.5476) (xy -3.2131 -12.5476) (xy -3.2131 13.208) (xy 3.2131 13.208) (xy 3.2131 0.00635)
				(xy 3.9751 0.00635) (xy 3.9751 1.3843) (xy 3.7211 1.3843) (xy 3.7211 13.716)
			)
			(stroke
				(width 0)
				(type default)
			)
			(fill no)
			(layer "F.CrtYd")
		)
		(fp_poly
			(pts
				(xy -3.7211 13.716) (xy -3.7211 1.7272) (xy -3.9751 1.7272) (xy -3.9751 -1.7272) (xy -3.7211 -1.7272)
				(xy -3.7211 -9.3218) (xy -3.9751 -9.3218) (xy -3.9751 -13.0556) (xy 3.9751 -13.0556) (xy 3.9751 -8.9662)
				(xy 3.7211 -8.9662) (xy 3.7211 -1.3843) (xy 3.9751 -1.3843) (xy 3.9751 1.3843) (xy 3.7211 1.3843)
				(xy 3.7211 13.716)
			)
			(stroke
				(width 0)
				(type default)
			)
			(fill no)
			(layer "F.Fab")
		)
		(pad "1" thru_hole circle
			(at -0.899922 -8.830056)
			(size 1.0668 1.0668)
			(drill 0.7112)
			(layers "*.Cu" "*.Mask")
			(remove_unused_layers no)
			(net "P5V_VBUS_CONN")
			(clearance 0.1778)
			(thermal_gap 0.1778)
		)
		(pad "2" thru_hole circle
			(at -0.899922 -6.329934)
			(size 1.0668 1.0668)
			(drill 0.7112)
			(layers "*.Cu" "*.Mask")
			(remove_unused_layers no)
			(net "USB_P1_F_DN1")
			(clearance 0.1778)
			(thermal_gap 0.1778)
		)
		(pad "3" thru_hole circle
			(at -0.899922 -4.329938)
			(size 1.0668 1.0668)
			(drill 0.7112)
			(layers "*.Cu" "*.Mask")
			(remove_unused_layers no)
			(net "USB_P1_F_DP1")
			(clearance 0.1778)
			(thermal_gap 0.1778)
		)
		(pad "4" thru_hole circle
			(at -0.899922 -1.829816)
			(size 1.0668 1.0668)
			(drill 0.7112)
			(layers "*.Cu" "*.Mask")
			(remove_unused_layers no)
			(net "GND")
			(clearance 0.1778)
			(thermal_gap 0.1778)
		)
		(pad "5" thru_hole circle
			(at 0.899922 -1.329944)
			(size 1.0668 1.0668)
			(drill 0.7112)
			(layers "*.Cu" "*.Mask")
			(remove_unused_layers no)
			(net "I2C_DEBUG_SCL")
			(clearance 0.1778)
			(thermal_gap 0.1778)
		)
		(pad "6" thru_hole circle
			(at 0.899922 -3.32994)
			(size 1.0668 1.0668)
			(drill 0.7112)
			(layers "*.Cu" "*.Mask")
			(remove_unused_layers no)
			(net "I2C_DEBUG_SDA")
			(clearance 0.1778)
			(thermal_gap 0.1778)
		)
		(pad "7" thru_hole circle
			(at 0.899922 -5.329936)
			(size 1.0668 1.0668)
			(drill 0.7112)
			(layers "*.Cu" "*.Mask")
			(remove_unused_layers no)
			(net "DEBUG_CARD_PRSNT")
			(clearance 0.1778)
			(thermal_gap 0.1778)
		)
		(pad "8" thru_hole circle
			(at 0.899922 -7.329932)
			(size 1.0668 1.0668)
			(drill 0.7112)
			(layers "*.Cu" "*.Mask")
			(remove_unused_layers no)
			(net "UART_IOM_TX")
			(clearance 0.1778)
			(thermal_gap 0.1778)
		)
		(pad "9" thru_hole circle
			(at 0.899922 -9.329928)
			(size 1.0668 1.0668)
			(drill 0.7112)
			(layers "*.Cu" "*.Mask")
			(remove_unused_layers no)
			(net "UART_IOM_RX")
			(clearance 0.1778)
			(thermal_gap 0.1778)
		)
		(pad "10" thru_hole oval
			(at -2.709926 -10.700004)
			(size 1.524 2.1336)
			(drill oval 0.8128 1.4224)
			(layers "*.Cu" "*.Mask")
			(remove_unused_layers no)
			(net "USB_CONN_GND")
			(clearance 0.1524)
			(thermal_gap 0.1524)
		)
		(pad "11" thru_hole oval
			(at -2.709926 0)
			(size 1.524 2.8194)
			(drill oval 0.8128 2.1082)
			(layers "*.Cu" "*.Mask")
			(remove_unused_layers no)
			(net "USB_CONN_GND")
			(clearance 0.1524)
			(thermal_gap 0.1524)
		)
		(pad "12" thru_hole oval
			(at 2.709926 0)
			(size 1.524 2.1336)
			(drill oval 0.8128 1.4224)
			(layers "*.Cu" "*.Mask")
			(remove_unused_layers no)
			(net "USB_CONN_GND")
			(clearance 0.1524)
			(thermal_gap 0.1524)
		)
		(pad "13" thru_hole oval
			(at 2.709926 -10.700004)
			(size 1.524 2.8194)
			(drill oval 0.8128 2.1082)
			(layers "*.Cu" "*.Mask")
			(remove_unused_layers no)
			(net "USB_CONN_GND")
			(clearance 0.1524)
			(thermal_gap 0.1524)
		)
	)
	(footprint ""
		(layer "F.Cu")
		(at 208.055972 -68.326 90)
		(property "Reference" "C317"
			(at 0 0 90)
			(layer "F.SilkS")
			(hide yes)
			(effects
				(font
					(size 1.27 1.27)
				)
			)
		)
		(property "Value" "SCD01U16V1KX-GP"
			(at -2.8321 -1.7399 90)
			(unlocked yes)
			(layer "F.Fab")
			(hide yes)
			(effects
				(font
					(size 1.016 1.016)
					(thickness 0.1524)
				)
			)
		)
		(property "Device Type" "C0201H13"
			(at -2.8321 -3.2639 90)
			(unlocked yes)
			(layer "F.Fab")
			(hide yes)
			(effects
				(font
					(size 1.016 1.016)
					(thickness 0.1524)
				)
			)
		)
		(duplicate_pad_numbers_are_jumpers no)
		(fp_rect
			(start -0.2794 0.6477)
			(end 0.2794 -0.6477)
			(stroke
				(width 0)
				(type default)
			)
			(fill no)
			(layer "F.CrtYd")
		)
		(fp_rect
			(start -0.2794 0.6477)
			(end 0.2794 -0.6477)
			(stroke
				(width 0)
				(type default)
			)
			(fill no)
			(layer "F.Fab")
		)
		(pad "1" smd custom
			(at 0 -0.2794 90)
			(size 0.0762 0.0762)
			(layers "F.Cu" "F.Mask" "F.Paste")
			(net "PHY_IOC_TO_CON_B_1_DP_C")
			(options
				(clearance outline)
				(anchor circle)
			)
			(primitives
				(gr_poly
					(pts
						(arc
							(start 0.1524 -0.127)
							(mid 0.137521 -0.162921)
							(end 0.1016 -0.1778)
						)
						(arc
							(start -0.1016 -0.1778)
							(mid -0.137521 -0.162921)
							(end -0.1524 -0.127)
						)
						(arc
							(start -0.1524 0.127)
							(mid -0.137521 0.162921)
							(end -0.1016 0.1778)
						)
						(arc
							(start 0.1016 0.1778)
							(mid 0.137521 0.162921)
							(end 0.1524 0.127)
						)
					)
					(width 0)
					(fill yes)
				)
			)
		)
		(pad "2" smd custom
			(at 0 0.2794 90)
			(size 0.0762 0.0762)
			(layers "F.Cu" "F.Mask" "F.Paste")
			(net "PHY_IOC_TO_CON_B_1_DP")
			(options
				(clearance outline)
				(anchor circle)
			)
			(primitives
				(gr_poly
					(pts
						(arc
							(start 0.1524 -0.127)
							(mid 0.137521 -0.162921)
							(end 0.1016 -0.1778)
						)
						(arc
							(start -0.1016 -0.1778)
							(mid -0.137521 -0.162921)
							(end -0.1524 -0.127)
						)
						(arc
							(start -0.1524 0.127)
							(mid -0.137521 0.162921)
							(end -0.1016 0.1778)
						)
						(arc
							(start 0.1016 0.1778)
							(mid 0.137521 0.162921)
							(end 0.1524 0.127)
						)
					)
					(width 0)
					(fill yes)
				)
			)
		)
	)
	(footprint ""
		(layer "F.Cu")
		(at 57.446672 -157.213808 90)
		(property "Reference" "TP53"
			(at 0 0 90)
			(layer "F.SilkS")
			(hide yes)
			(effects
				(font
					(size 1.27 1.27)
				)
			)
		)
		(property "Value" "TPAD28-2-GP"
			(at -0.0127 -1.6637 90)
			(unlocked yes)
			(layer "F.Fab")
			(hide yes)
			(effects
				(font
					(size 1.016 1.016)
					(thickness 0.1524)
				)
			)
		)
		(property "Device Type" "TPAD28"
			(at -0.0127 -3.1877 90)
			(unlocked yes)
			(layer "F.Fab")
			(hide yes)
			(effects
				(font
					(size 1.016 1.016)
					(thickness 0.1524)
				)
			)
		)
		(duplicate_pad_numbers_are_jumpers no)
		(fp_poly
			(pts
				(arc
					(start 0 0.3556)
					(mid 0 -0.3556)
					(end 0 0.3556)
				)
			)
			(stroke
				(width 0)
				(type default)
			)
			(fill no)
			(layer "F.CrtYd")
		)
		(fp_poly
			(pts
				(arc
					(start 0 0.6096)
					(mid 0 -0.6096)
					(end 0 0.6096)
				)
			)
			(stroke
				(width 0)
				(type default)
			)
			(fill no)
			(layer "F.Fab")
		)
		(pad "1" smd circle
			(at 0 0 90)
			(size 0.7112 0.7112)
			(layers "F.Cu" "F.Mask" "F.Paste")
			(net "TP_BMC_GPIOT6")
		)
	)
	(footprint ""
		(layer "F.Cu")
		(at 35.687 -157.5562)
		(property "Reference" "TP57"
			(at 0 0 0)
			(layer "F.SilkS")
			(hide yes)
			(effects
				(font
					(size 1.27 1.27)
				)
			)
		)
		(property "Value" "TPAD28-2-GP"
			(at -0.0127 -1.6637 0)
			(unlocked yes)
			(layer "F.Fab")
			(hide yes)
			(effects
				(font
					(size 1.016 1.016)
					(thickness 0.1524)
				)
			)
		)
		(property "Device Type" "TPAD28"
			(at -0.0127 -3.1877 0)
			(unlocked yes)
			(layer "F.Fab")
			(hide yes)
			(effects
				(font
					(size 1.016 1.016)
					(thickness 0.1524)
				)
			)
		)
		(duplicate_pad_numbers_are_jumpers no)
		(fp_poly
			(pts
				(arc
					(start 0.3556 0)
					(mid -0.3556 0)
					(end 0.3556 0)
				)
			)
			(stroke
				(width 0)
				(type default)
			)
			(fill no)
			(layer "F.CrtYd")
		)
		(fp_poly
			(pts
				(arc
					(start 0.6096 0)
					(mid -0.6096 0)
					(end 0.6096 0)
				)
			)
			(stroke
				(width 0)
				(type default)
			)
			(fill no)
			(layer "F.Fab")
		)
		(pad "1" smd circle
			(at 0 0)
			(size 0.7112 0.7112)
			(layers "F.Cu" "F.Mask" "F.Paste")
			(net "TP_BMC_GPION5")
		)
	)
)
